FILE_TYPE = MACRO_DRAWING;
SET COLOR_WIRE YELLOW;
SET COLOR_PROP ORANGE;
SET COLOR_DOT WHITE;
SET COLOR_ARC YELLOW;
SET COLOR_BODY GREEN;
SET COLOR_NOTE PURPLE;
SET PROP_DISPLAY VALUE;
SET PAGE_NUMBER P386;
FORCEADD UNIVERSAL_GND..1
(-7400 3100);
FORCEPROP 3 LASTPIN (-7400 3150) SIG_NAME GND\g
J 0
(-7390 3160);
DISPLAY 0.659574 (-7390 3160);
PAINT MONO (-7390 3160);
DISPLAY INVISIBLE (-7390 3160);
FORCEPROP 2 LAST CDS_LIB pure_quanta_power
J 0
(-7400 3100);
DISPLAY INVISIBLE (-7400 3100);
FORCEPROP 1 LAST HDL_POWER GND
J 1
(-7375 3025);
DISPLAY 0.872340 (-7375 3025);
PAINT GREEN (-7375 3025);
DISPLAY INVISIBLE (-7375 3025);
FORCEPROP 1 LAST PATH I1
J 0
(-7325 3100);
DISPLAY 0.872340 (-7325 3100);
PAINT AQUA (-7325 3100);
DISPLAY INVISIBLE (-7325 3100);
FORCEADD UNIVERSAL_GND..1
(-2875 1325);
FORCEPROP 3 LASTPIN (-2875 1375) SIG_NAME GND\g
J 0
(-2865 1385);
DISPLAY 0.659574 (-2865 1385);
PAINT MONO (-2865 1385);
DISPLAY INVISIBLE (-2865 1385);
FORCEPROP 2 LAST CDS_LIB pure_quanta_power
J 0
(-2875 1325);
DISPLAY INVISIBLE (-2875 1325);
FORCEPROP 1 LAST HDL_POWER GND
J 1
(-2850 1250);
DISPLAY 0.872340 (-2850 1250);
PAINT GREEN (-2850 1250);
DISPLAY INVISIBLE (-2850 1250);
FORCEPROP 1 LAST PATH I10
J 0
(-2800 1325);
DISPLAY 0.872340 (-2800 1325);
PAINT AQUA (-2800 1325);
DISPLAY INVISIBLE (-2800 1325);
FORCEADD P1V0..1
(-4400 3800);
FORCEPROP 3 LASTPIN (-4400 3750) SIG_NAME P0V9_CPU0_RT_2D\g
J 0
(-4390 3760);
DISPLAY 0.659574 (-4390 3760);
PAINT MONO (-4390 3760);
DISPLAY INVISIBLE (-4390 3760);
FORCEPROP 1 LAST HDL_POWER P0V9_CPU0_RT_2D
J 1
(-4400 3850);
DISPLAY 0.489362 (-4400 3850);
PAINT SKYBLUE (-4400 3850);
FORCEPROP 2 LAST CDS_LIB pure_quanta_power
J 0
(-4400 3800);
DISPLAY INVISIBLE (-4400 3800);
FORCEPROP 1 LAST PATH I11
J 0
(-4350 3825);
DISPLAY 0.872340 (-4350 3825);
PAINT AQUA (-4350 3825);
DISPLAY INVISIBLE (-4350 3825);
FORCEADD UNIVERSAL_GND..1
(-1200 950);
FORCEPROP 3 LASTPIN (-1200 1000) SIG_NAME GND\g
J 0
(-1190 1010);
DISPLAY 0.659574 (-1190 1010);
PAINT MONO (-1190 1010);
DISPLAY INVISIBLE (-1190 1010);
FORCEPROP 2 LAST CDS_LIB pure_quanta_power
J 0
(-1200 950);
DISPLAY INVISIBLE (-1200 950);
FORCEPROP 1 LAST HDL_POWER GND
J 1
(-1175 875);
DISPLAY 0.872340 (-1175 875);
PAINT GREEN (-1175 875);
DISPLAY INVISIBLE (-1175 875);
FORCEPROP 1 LAST PATH I12
J 0
(-1125 950);
DISPLAY 0.872340 (-1125 950);
PAINT AQUA (-1125 950);
DISPLAY INVISIBLE (-1125 950);
FORCEADD Q_RES..2
(-1200 1250);
FORCEPROP 1 LAST LOCATION R6821
J 0
(-1155 1375);
DISPLAY 0.978723 (-1155 1375);
FORCEPROP 0 LAST $SEC 1
J 0
(-1150 1425);
DISPLAY 0.680851 (-1150 1425);
PAINT MONO (-1150 1425);
DISPLAY INVISIBLE (-1150 1425);
FORCEPROP 0 LAST CDS_SEC 1
J 0
(-1150 1425);
DISPLAY 0.680851 (-1150 1425);
DISPLAY INVISIBLE (-1150 1425);
FORCEPROP 1 LASTPIN (-1200 1350) $PN 1
J 0
(-1195 1312);
DISPLAY 0.787234 (-1195 1312);
PAINT MONO (-1195 1312);
FORCEPROP 1 LASTPIN (-1200 1150) $PN 2
J 0
(-1195 1160);
DISPLAY 0.787234 (-1195 1160);
PAINT MONO (-1195 1160);
FORCEPROP 1 LAST PACK_TYPE 0201LF
J 0
(-1160 1075);
DISPLAY 0.978723 (-1160 1075);
FORCEPROP 1 LAST VALUE 0
J 0
(-1155 1325);
DISPLAY 0.978723 (-1155 1325);
FORCEPROP 1 LAST TOLERANCE 5%
J 0
(-1155 1275);
DISPLAY 0.978723 (-1155 1275);
FORCEPROP 1 LAST WATTAGE 1/20W
J 0
(-1160 1225);
DISPLAY 0.978723 (-1160 1225);
FORCEPROP 1 LAST MATERIAL CHIP
J 0
(-1160 1175);
DISPLAY 0.978723 (-1160 1175);
FORCEPROP 2 LAST CDS_LIB pure_quanta
J 0
(-1200 1250);
DISPLAY INVISIBLE (-1200 1250);
FORCEPROP 1 LAST PATH I13
J 0
(-1150 1425);
DISPLAY 0.978723 (-1150 1425);
PAINT WHITE (-1150 1425);
DISPLAY INVISIBLE (-1150 1425);
FORCEPROP 1 LAST PART_NUMBER CS00001JE10
J 0
(-1160 1125);
DISPLAY 0.978723 (-1160 1125);
DISPLAY INVISIBLE (-1160 1125);
FORCEADD UNIVERSAL_GND..1
(-1050 1500);
FORCEPROP 3 LASTPIN (-1050 1550) SIG_NAME GND\g
J 0
(-1040 1560);
DISPLAY 0.659574 (-1040 1560);
PAINT MONO (-1040 1560);
DISPLAY INVISIBLE (-1040 1560);
FORCEPROP 2 LAST CDS_LIB pure_quanta_power
J 0
(-1050 1500);
DISPLAY INVISIBLE (-1050 1500);
FORCEPROP 1 LAST HDL_POWER GND
J 1
(-1025 1425);
DISPLAY 0.872340 (-1025 1425);
PAINT GREEN (-1025 1425);
DISPLAY INVISIBLE (-1025 1425);
FORCEPROP 1 LAST PATH I14
J 0
(-975 1500);
DISPLAY 0.872340 (-975 1500);
PAINT AQUA (-975 1500);
DISPLAY INVISIBLE (-975 1500);
FORCEADD Q_RES..2
(-1050 1800);
FORCEPROP 1 LAST LOCATION R6820
J 0
(-1005 1925);
DISPLAY 0.978723 (-1005 1925);
FORCEPROP 0 LAST $SEC 1
J 0
(-1000 1975);
DISPLAY 0.680851 (-1000 1975);
PAINT MONO (-1000 1975);
DISPLAY INVISIBLE (-1000 1975);
FORCEPROP 0 LAST CDS_SEC 1
J 0
(-1000 1975);
DISPLAY 0.680851 (-1000 1975);
DISPLAY INVISIBLE (-1000 1975);
FORCEPROP 1 LASTPIN (-1050 1900) $PN 1
J 0
(-1045 1862);
DISPLAY 0.787234 (-1045 1862);
PAINT MONO (-1045 1862);
FORCEPROP 1 LASTPIN (-1050 1700) $PN 2
J 0
(-1045 1710);
DISPLAY 0.787234 (-1045 1710);
PAINT MONO (-1045 1710);
FORCEPROP 1 LAST PACK_TYPE 0201LF
J 0
(-1010 1625);
DISPLAY 0.978723 (-1010 1625);
FORCEPROP 1 LAST MATERIAL CHIP
J 0
(-1010 1725);
DISPLAY 0.978723 (-1010 1725);
FORCEPROP 1 LAST TOLERANCE 5%
J 0
(-1005 1825);
DISPLAY 0.978723 (-1005 1825);
FORCEPROP 1 LAST VALUE 0
J 0
(-1005 1875);
DISPLAY 0.978723 (-1005 1875);
FORCEPROP 1 LAST WATTAGE 1/20W
J 0
(-1010 1775);
DISPLAY 0.978723 (-1010 1775);
FORCEPROP 2 LAST CDS_LIB pure_quanta
J 0
(-1050 1800);
DISPLAY INVISIBLE (-1050 1800);
FORCEPROP 1 LAST PATH I15
J 0
(-1000 1975);
DISPLAY 0.978723 (-1000 1975);
PAINT WHITE (-1000 1975);
DISPLAY INVISIBLE (-1000 1975);
FORCEPROP 1 LAST PART_NUMBER CS00001JE10
J 0
(-1010 1675);
DISPLAY 0.978723 (-1010 1675);
DISPLAY INVISIBLE (-1010 1675);
FORCEADD UNIVERSAL_GND..1
(-825 2050);
FORCEPROP 3 LASTPIN (-825 2100) SIG_NAME GND\g
J 0
(-815 2110);
DISPLAY 0.659574 (-815 2110);
PAINT MONO (-815 2110);
DISPLAY INVISIBLE (-815 2110);
FORCEPROP 2 LAST CDS_LIB pure_quanta_power
J 0
(-825 2050);
DISPLAY INVISIBLE (-825 2050);
FORCEPROP 1 LAST HDL_POWER GND
J 1
(-800 1975);
DISPLAY 0.872340 (-800 1975);
PAINT GREEN (-800 1975);
DISPLAY INVISIBLE (-800 1975);
FORCEPROP 1 LAST PATH I16
J 0
(-750 2050);
DISPLAY 0.872340 (-750 2050);
PAINT AQUA (-750 2050);
DISPLAY INVISIBLE (-750 2050);
FORCEADD PT5161LRS..5
(-2175 3575);
FORCEPROP 1 LAST LOCATION U6010
J 0
(-2525 5900);
DISPLAY 0.723404 (-2525 5900);
PAINT SKYBLUE (-2525 5900);
FORCEPROP 0 LAST $SEC 5
J 0
(-2525 6050);
DISPLAY 0.680851 (-2525 6050);
PAINT MONO (-2525 6050);
DISPLAY INVISIBLE (-2525 6050);
FORCEPROP 0 LAST CDS_SEC 5
J 0
(-2525 6050);
DISPLAY 0.680851 (-2525 6050);
DISPLAY INVISIBLE (-2525 6050);
FORCEPROP 0 LASTPIN (-2675 5575) $PN AC13
J 2
(-2685 5585);
DISPLAY 0.680851 (-2685 5585);
PAINT MONO (-2685 5585);
FORCEPROP 0 LASTPIN (-2675 5525) $PN AC22
J 2
(-2685 5535);
DISPLAY 0.680851 (-2685 5535);
PAINT MONO (-2685 5535);
FORCEPROP 0 LASTPIN (-2675 5475) $PN AC32
J 2
(-2685 5485);
DISPLAY 0.680851 (-2685 5485);
PAINT MONO (-2685 5485);
FORCEPROP 0 LASTPIN (-2675 5425) $PN AC4
J 2
(-2685 5435);
DISPLAY 0.680851 (-2685 5435);
PAINT MONO (-2685 5435);
FORCEPROP 0 LASTPIN (-2675 5375) $PN AD2
J 2
(-2685 5385);
DISPLAY 0.680851 (-2685 5385);
PAINT MONO (-2685 5385);
FORCEPROP 0 LASTPIN (-2675 5325) $PN AD34
J 2
(-2685 5335);
DISPLAY 0.680851 (-2685 5335);
PAINT MONO (-2685 5335);
FORCEPROP 0 LASTPIN (-2675 5275) $PN AE1
J 2
(-2685 5285);
DISPLAY 0.680851 (-2685 5285);
PAINT MONO (-2685 5285);
FORCEPROP 0 LASTPIN (-2675 5225) $PN AE35
J 2
(-2685 5235);
DISPLAY 0.680851 (-2685 5235);
PAINT MONO (-2685 5235);
FORCEPROP 0 LASTPIN (-2675 5175) $PN AK13
J 2
(-2685 5185);
DISPLAY 0.680851 (-2685 5185);
PAINT MONO (-2685 5185);
FORCEPROP 0 LASTPIN (-2675 5125) $PN AK22
J 2
(-2685 5135);
DISPLAY 0.680851 (-2685 5135);
PAINT MONO (-2685 5135);
FORCEPROP 0 LASTPIN (-2675 5075) $PN AK32
J 2
(-2685 5085);
DISPLAY 0.680851 (-2685 5085);
PAINT MONO (-2685 5085);
FORCEPROP 0 LASTPIN (-2675 5025) $PN AK4
J 2
(-2685 5035);
DISPLAY 0.680851 (-2685 5035);
PAINT MONO (-2685 5035);
FORCEPROP 0 LASTPIN (-2675 4975) $PN AL2
J 2
(-2685 4985);
DISPLAY 0.680851 (-2685 4985);
PAINT MONO (-2685 4985);
FORCEPROP 0 LASTPIN (-2675 4925) $PN AL34
J 2
(-2685 4935);
DISPLAY 0.680851 (-2685 4935);
PAINT MONO (-2685 4935);
FORCEPROP 0 LASTPIN (-2675 4875) $PN AM1
J 2
(-2685 4885);
DISPLAY 0.680851 (-2685 4885);
PAINT MONO (-2685 4885);
FORCEPROP 0 LASTPIN (-2675 4825) $PN AM35
J 2
(-2685 4835);
DISPLAY 0.680851 (-2685 4835);
PAINT MONO (-2685 4835);
FORCEPROP 0 LASTPIN (-2675 4775) $PN AU13
J 2
(-2685 4785);
DISPLAY 0.680851 (-2685 4785);
PAINT MONO (-2685 4785);
FORCEPROP 0 LASTPIN (-2675 4725) $PN AU22
J 2
(-2685 4735);
DISPLAY 0.680851 (-2685 4735);
PAINT MONO (-2685 4735);
FORCEPROP 0 LASTPIN (-2675 4675) $PN AU32
J 2
(-2685 4685);
DISPLAY 0.680851 (-2685 4685);
PAINT MONO (-2685 4685);
FORCEPROP 0 LASTPIN (-2675 4625) $PN AU4
J 2
(-2685 4635);
DISPLAY 0.680851 (-2685 4635);
PAINT MONO (-2685 4635);
FORCEPROP 0 LASTPIN (-2675 4575) $PN AV2
J 2
(-2685 4585);
DISPLAY 0.680851 (-2685 4585);
PAINT MONO (-2685 4585);
FORCEPROP 0 LASTPIN (-2675 4525) $PN AV34
J 2
(-2685 4535);
DISPLAY 0.680851 (-2685 4535);
PAINT MONO (-2685 4535);
FORCEPROP 0 LASTPIN (-2675 4475) $PN AW1
J 2
(-2685 4485);
DISPLAY 0.680851 (-2685 4485);
PAINT MONO (-2685 4485);
FORCEPROP 0 LASTPIN (-2675 4425) $PN AW35
J 2
(-2685 4435);
DISPLAY 0.680851 (-2685 4435);
PAINT MONO (-2685 4435);
FORCEPROP 0 LASTPIN (-2675 4375) $PN B19
J 2
(-2685 4385);
DISPLAY 0.680851 (-2685 4385);
PAINT MONO (-2685 4385);
FORCEPROP 0 LASTPIN (-2675 4325) $PN BD13
J 2
(-2685 4335);
DISPLAY 0.680851 (-2685 4335);
PAINT MONO (-2685 4335);
FORCEPROP 0 LASTPIN (-2675 4275) $PN BD22
J 2
(-2685 4285);
DISPLAY 0.680851 (-2685 4285);
PAINT MONO (-2685 4285);
FORCEPROP 0 LASTPIN (-2675 4225) $PN BD32
J 2
(-2685 4235);
DISPLAY 0.680851 (-2685 4235);
PAINT MONO (-2685 4235);
FORCEPROP 0 LASTPIN (-2675 4175) $PN BD4
J 2
(-2685 4185);
DISPLAY 0.680851 (-2685 4185);
PAINT MONO (-2685 4185);
FORCEPROP 0 LASTPIN (-2675 4125) $PN BE2
J 2
(-2685 4135);
DISPLAY 0.680851 (-2685 4135);
PAINT MONO (-2685 4135);
FORCEPROP 0 LASTPIN (-2675 4075) $PN BE34
J 2
(-2685 4085);
DISPLAY 0.680851 (-2685 4085);
PAINT MONO (-2685 4085);
FORCEPROP 0 LASTPIN (-2675 4025) $PN BF1
J 2
(-2685 4035);
DISPLAY 0.680851 (-2685 4035);
PAINT MONO (-2685 4035);
FORCEPROP 0 LASTPIN (-2675 3975) $PN BF35
J 2
(-2685 3985);
DISPLAY 0.680851 (-2685 3985);
PAINT MONO (-2685 3985);
FORCEPROP 0 LASTPIN (-2675 3925) $PN BL13
J 2
(-2685 3935);
DISPLAY 0.680851 (-2685 3935);
PAINT MONO (-2685 3935);
FORCEPROP 0 LASTPIN (-2675 3875) $PN BL22
J 2
(-2685 3885);
DISPLAY 0.680851 (-2685 3885);
PAINT MONO (-2685 3885);
FORCEPROP 0 LASTPIN (-2675 3825) $PN BL32
J 2
(-2685 3835);
DISPLAY 0.680851 (-2685 3835);
PAINT MONO (-2685 3835);
FORCEPROP 0 LASTPIN (-2675 3775) $PN BL4
J 2
(-2685 3785);
DISPLAY 0.680851 (-2685 3785);
PAINT MONO (-2685 3785);
FORCEPROP 0 LASTPIN (-2675 3725) $PN BM2
J 2
(-2685 3735);
DISPLAY 0.680851 (-2685 3735);
PAINT MONO (-2685 3735);
FORCEPROP 0 LASTPIN (-2675 3675) $PN BM34
J 2
(-2685 3685);
DISPLAY 0.680851 (-2685 3685);
PAINT MONO (-2685 3685);
FORCEPROP 0 LASTPIN (-2675 3625) $PN BN1
J 2
(-2685 3635);
DISPLAY 0.680851 (-2685 3635);
PAINT MONO (-2685 3635);
FORCEPROP 0 LASTPIN (-2675 3575) $PN BN35
J 2
(-2685 3585);
DISPLAY 0.680851 (-2685 3585);
PAINT MONO (-2685 3585);
FORCEPROP 0 LASTPIN (-2675 3525) $PN BV13
J 2
(-2685 3535);
DISPLAY 0.680851 (-2685 3535);
PAINT MONO (-2685 3535);
FORCEPROP 0 LASTPIN (-2675 3475) $PN BV22
J 2
(-2685 3485);
DISPLAY 0.680851 (-2685 3485);
PAINT MONO (-2685 3485);
FORCEPROP 0 LASTPIN (-2675 3425) $PN BV32
J 2
(-2685 3435);
DISPLAY 0.680851 (-2685 3435);
PAINT MONO (-2685 3435);
FORCEPROP 0 LASTPIN (-2675 3375) $PN BV4
J 2
(-2685 3385);
DISPLAY 0.680851 (-2685 3385);
PAINT MONO (-2685 3385);
FORCEPROP 0 LASTPIN (-2675 3325) $PN BW2
J 2
(-2685 3335);
DISPLAY 0.680851 (-2685 3335);
PAINT MONO (-2685 3335);
FORCEPROP 0 LASTPIN (-2675 3275) $PN BW34
J 2
(-2685 3285);
DISPLAY 0.680851 (-2685 3285);
PAINT MONO (-2685 3285);
FORCEPROP 0 LASTPIN (-2675 3225) $PN BY1
J 2
(-2685 3235);
DISPLAY 0.680851 (-2685 3235);
PAINT MONO (-2685 3235);
FORCEPROP 0 LASTPIN (-2675 3175) $PN BY35
J 2
(-2685 3185);
DISPLAY 0.680851 (-2685 3185);
PAINT MONO (-2685 3185);
FORCEPROP 0 LASTPIN (-2675 3125) $PN CE13
J 2
(-2685 3135);
DISPLAY 0.680851 (-2685 3135);
PAINT MONO (-2685 3135);
FORCEPROP 0 LASTPIN (-2675 3075) $PN CE22
J 2
(-2685 3085);
DISPLAY 0.680851 (-2685 3085);
PAINT MONO (-2685 3085);
FORCEPROP 0 LASTPIN (-2675 3025) $PN CE32
J 2
(-2685 3035);
DISPLAY 0.680851 (-2685 3035);
PAINT MONO (-2685 3035);
FORCEPROP 0 LASTPIN (-2675 2975) $PN CE4
J 2
(-2685 2985);
DISPLAY 0.680851 (-2685 2985);
PAINT MONO (-2685 2985);
FORCEPROP 0 LASTPIN (-2675 2925) $PN CF2
J 2
(-2685 2935);
DISPLAY 0.680851 (-2685 2935);
PAINT MONO (-2685 2935);
FORCEPROP 0 LASTPIN (-2675 2875) $PN CF34
J 2
(-2685 2885);
DISPLAY 0.680851 (-2685 2885);
PAINT MONO (-2685 2885);
FORCEPROP 0 LASTPIN (-2675 2825) $PN CG1
J 2
(-2685 2835);
DISPLAY 0.680851 (-2685 2835);
PAINT MONO (-2685 2835);
FORCEPROP 0 LASTPIN (-2675 2775) $PN CG35
J 2
(-2685 2785);
DISPLAY 0.680851 (-2685 2785);
PAINT MONO (-2685 2785);
FORCEPROP 0 LASTPIN (-2675 2725) $PN CM13
J 2
(-2685 2735);
DISPLAY 0.680851 (-2685 2735);
PAINT MONO (-2685 2735);
FORCEPROP 0 LASTPIN (-2675 2675) $PN CM22
J 2
(-2685 2685);
DISPLAY 0.680851 (-2685 2685);
PAINT MONO (-2685 2685);
FORCEPROP 0 LASTPIN (-2675 2625) $PN CM32
J 2
(-2685 2635);
DISPLAY 0.680851 (-2685 2635);
PAINT MONO (-2685 2635);
FORCEPROP 0 LASTPIN (-2675 2575) $PN CM4
J 2
(-2685 2585);
DISPLAY 0.680851 (-2685 2585);
PAINT MONO (-2685 2585);
FORCEPROP 0 LASTPIN (-2675 2525) $PN CN2
J 2
(-2685 2535);
DISPLAY 0.680851 (-2685 2535);
PAINT MONO (-2685 2535);
FORCEPROP 0 LASTPIN (-2675 2475) $PN CN34
J 2
(-2685 2485);
DISPLAY 0.680851 (-2685 2485);
PAINT MONO (-2685 2485);
FORCEPROP 0 LASTPIN (-2675 2425) $PN CP1
J 2
(-2685 2435);
DISPLAY 0.680851 (-2685 2435);
PAINT MONO (-2685 2435);
FORCEPROP 0 LASTPIN (-2675 2375) $PN CP35
J 2
(-2685 2385);
DISPLAY 0.680851 (-2685 2385);
PAINT MONO (-2685 2385);
FORCEPROP 0 LASTPIN (-2675 2325) $PN CW13
J 2
(-2685 2335);
DISPLAY 0.680851 (-2685 2335);
PAINT MONO (-2685 2335);
FORCEPROP 0 LASTPIN (-2675 2275) $PN CW22
J 2
(-2685 2285);
DISPLAY 0.680851 (-2685 2285);
PAINT MONO (-2685 2285);
FORCEPROP 0 LASTPIN (-2675 2225) $PN CW32
J 2
(-2685 2235);
DISPLAY 0.680851 (-2685 2235);
PAINT MONO (-2685 2235);
FORCEPROP 0 LASTPIN (-2675 2175) $PN CW4
J 2
(-2685 2185);
DISPLAY 0.680851 (-2685 2185);
PAINT MONO (-2685 2185);
FORCEPROP 0 LASTPIN (-2675 2125) $PN CY2
J 2
(-2685 2135);
DISPLAY 0.680851 (-2685 2135);
PAINT MONO (-2685 2135);
FORCEPROP 0 LASTPIN (-2675 2075) $PN CY34
J 2
(-2685 2085);
DISPLAY 0.680851 (-2685 2085);
PAINT MONO (-2685 2085);
FORCEPROP 0 LASTPIN (-2675 2025) $PN DA1
J 2
(-2685 2035);
DISPLAY 0.680851 (-2685 2035);
PAINT MONO (-2685 2035);
FORCEPROP 0 LASTPIN (-2675 1975) $PN DA35
J 2
(-2685 1985);
DISPLAY 0.680851 (-2685 1985);
PAINT MONO (-2685 1985);
FORCEPROP 0 LASTPIN (-2675 1925) $PN DF13
J 2
(-2685 1935);
DISPLAY 0.680851 (-2685 1935);
PAINT MONO (-2685 1935);
FORCEPROP 0 LASTPIN (-2675 1875) $PN DF22
J 2
(-2685 1885);
DISPLAY 0.680851 (-2685 1885);
PAINT MONO (-2685 1885);
FORCEPROP 0 LASTPIN (-2675 1825) $PN DF32
J 2
(-2685 1835);
DISPLAY 0.680851 (-2685 1835);
PAINT MONO (-2685 1835);
FORCEPROP 0 LASTPIN (-2675 1775) $PN DF4
J 2
(-2685 1785);
DISPLAY 0.680851 (-2685 1785);
PAINT MONO (-2685 1785);
FORCEPROP 0 LASTPIN (-2675 1725) $PN DG2
J 2
(-2685 1735);
DISPLAY 0.680851 (-2685 1735);
PAINT MONO (-2685 1735);
FORCEPROP 0 LASTPIN (-2675 1675) $PN DG34
J 2
(-2685 1685);
DISPLAY 0.680851 (-2685 1685);
PAINT MONO (-2685 1685);
FORCEPROP 0 LASTPIN (-2675 1625) $PN DH1
J 2
(-2685 1635);
DISPLAY 0.680851 (-2685 1635);
PAINT MONO (-2685 1635);
FORCEPROP 0 LASTPIN (-2675 1575) $PN DH35
J 2
(-2685 1585);
DISPLAY 0.680851 (-2685 1585);
PAINT MONO (-2685 1585);
FORCEPROP 0 LASTPIN (-2675 1525) $PN DN13
J 2
(-2685 1535);
DISPLAY 0.680851 (-2685 1535);
PAINT MONO (-2685 1535);
FORCEPROP 0 LASTPIN (-1725 5575) $PN DN22
J 0
(-1715 5585);
DISPLAY 0.680851 (-1715 5585);
PAINT MONO (-1715 5585);
FORCEPROP 0 LASTPIN (-1725 5525) $PN DN32
J 0
(-1715 5535);
DISPLAY 0.680851 (-1715 5535);
PAINT MONO (-1715 5535);
FORCEPROP 0 LASTPIN (-1725 5475) $PN DN4
J 0
(-1715 5485);
DISPLAY 0.680851 (-1715 5485);
PAINT MONO (-1715 5485);
FORCEPROP 0 LASTPIN (-1725 5425) $PN DP2
J 0
(-1715 5435);
DISPLAY 0.680851 (-1715 5435);
PAINT MONO (-1715 5435);
FORCEPROP 0 LASTPIN (-1725 5375) $PN DP34
J 0
(-1715 5385);
DISPLAY 0.680851 (-1715 5385);
PAINT MONO (-1715 5385);
FORCEPROP 0 LASTPIN (-1725 5325) $PN DR1
J 0
(-1715 5335);
DISPLAY 0.680851 (-1715 5335);
PAINT MONO (-1715 5335);
FORCEPROP 0 LASTPIN (-1725 5275) $PN DR35
J 0
(-1715 5285);
DISPLAY 0.680851 (-1715 5285);
PAINT MONO (-1715 5285);
FORCEPROP 0 LASTPIN (-1725 5225) $PN DY13
J 0
(-1715 5235);
DISPLAY 0.680851 (-1715 5235);
PAINT MONO (-1715 5235);
FORCEPROP 0 LASTPIN (-1725 5175) $PN DY22
J 0
(-1715 5185);
DISPLAY 0.680851 (-1715 5185);
PAINT MONO (-1715 5185);
FORCEPROP 0 LASTPIN (-1725 5125) $PN DY32
J 0
(-1715 5135);
DISPLAY 0.680851 (-1715 5135);
PAINT MONO (-1715 5135);
FORCEPROP 0 LASTPIN (-1725 5075) $PN DY4
J 0
(-1715 5085);
DISPLAY 0.680851 (-1715 5085);
PAINT MONO (-1715 5085);
FORCEPROP 0 LASTPIN (-1725 5025) $PN E14
J 0
(-1715 5035);
DISPLAY 0.680851 (-1715 5035);
PAINT MONO (-1715 5035);
FORCEPROP 0 LASTPIN (-1725 4975) $PN E27
J 0
(-1715 4985);
DISPLAY 0.680851 (-1715 4985);
PAINT MONO (-1715 4985);
FORCEPROP 0 LASTPIN (-1725 4925) $PN E33
J 0
(-1715 4935);
DISPLAY 0.680851 (-1715 4935);
PAINT MONO (-1715 4935);
FORCEPROP 0 LASTPIN (-1725 4875) $PN EA2
J 0
(-1715 4885);
DISPLAY 0.680851 (-1715 4885);
PAINT MONO (-1715 4885);
FORCEPROP 0 LASTPIN (-1725 4825) $PN EA34
J 0
(-1715 4835);
DISPLAY 0.680851 (-1715 4835);
PAINT MONO (-1715 4835);
FORCEPROP 0 LASTPIN (-1725 4775) $PN EB1
J 0
(-1715 4785);
DISPLAY 0.680851 (-1715 4785);
PAINT MONO (-1715 4785);
FORCEPROP 0 LASTPIN (-1725 4725) $PN EB35
J 0
(-1715 4735);
DISPLAY 0.680851 (-1715 4735);
PAINT MONO (-1715 4735);
FORCEPROP 0 LASTPIN (-1725 4675) $PN EG13
J 0
(-1715 4685);
DISPLAY 0.680851 (-1715 4685);
PAINT MONO (-1715 4685);
FORCEPROP 0 LASTPIN (-1725 4625) $PN EG22
J 0
(-1715 4635);
DISPLAY 0.680851 (-1715 4635);
PAINT MONO (-1715 4635);
FORCEPROP 0 LASTPIN (-1725 4575) $PN EG32
J 0
(-1715 4585);
DISPLAY 0.680851 (-1715 4585);
PAINT MONO (-1715 4585);
FORCEPROP 0 LASTPIN (-1725 4525) $PN EG4
J 0
(-1715 4535);
DISPLAY 0.680851 (-1715 4535);
PAINT MONO (-1715 4535);
FORCEPROP 0 LASTPIN (-1725 4475) $PN EH2
J 0
(-1715 4485);
DISPLAY 0.680851 (-1715 4485);
PAINT MONO (-1715 4485);
FORCEPROP 0 LASTPIN (-1725 4425) $PN EH34
J 0
(-1715 4435);
DISPLAY 0.680851 (-1715 4435);
PAINT MONO (-1715 4435);
FORCEPROP 0 LASTPIN (-1725 4375) $PN EJ1
J 0
(-1715 4385);
DISPLAY 0.680851 (-1715 4385);
PAINT MONO (-1715 4385);
FORCEPROP 0 LASTPIN (-1725 4325) $PN EJ35
J 0
(-1715 4335);
DISPLAY 0.680851 (-1715 4335);
PAINT MONO (-1715 4335);
FORCEPROP 0 LASTPIN (-1725 4275) $PN EP13
J 0
(-1715 4285);
DISPLAY 0.680851 (-1715 4285);
PAINT MONO (-1715 4285);
FORCEPROP 0 LASTPIN (-1725 4225) $PN EP22
J 0
(-1715 4235);
DISPLAY 0.680851 (-1715 4235);
PAINT MONO (-1715 4235);
FORCEPROP 0 LASTPIN (-1725 4175) $PN EP32
J 0
(-1715 4185);
DISPLAY 0.680851 (-1715 4185);
PAINT MONO (-1715 4185);
FORCEPROP 0 LASTPIN (-1725 4125) $PN EP4
J 0
(-1715 4135);
DISPLAY 0.680851 (-1715 4135);
PAINT MONO (-1715 4135);
FORCEPROP 0 LASTPIN (-1725 4075) $PN ER2
J 0
(-1715 4085);
DISPLAY 0.680851 (-1715 4085);
PAINT MONO (-1715 4085);
FORCEPROP 0 LASTPIN (-1725 4025) $PN ER34
J 0
(-1715 4035);
DISPLAY 0.680851 (-1715 4035);
PAINT MONO (-1715 4035);
FORCEPROP 0 LASTPIN (-1725 3975) $PN ET1
J 0
(-1715 3985);
DISPLAY 0.680851 (-1715 3985);
PAINT MONO (-1715 3985);
FORCEPROP 0 LASTPIN (-1725 3925) $PN ET35
J 0
(-1715 3935);
DISPLAY 0.680851 (-1715 3935);
PAINT MONO (-1715 3935);
FORCEPROP 0 LASTPIN (-1725 3875) $PN FA15
J 0
(-1715 3885);
DISPLAY 0.680851 (-1715 3885);
PAINT MONO (-1715 3885);
FORCEPROP 0 LASTPIN (-1725 3825) $PN FA32
J 0
(-1715 3835);
DISPLAY 0.680851 (-1715 3835);
PAINT MONO (-1715 3835);
FORCEPROP 0 LASTPIN (-1725 3775) $PN FB2
J 0
(-1715 3785);
DISPLAY 0.680851 (-1715 3785);
PAINT MONO (-1715 3785);
FORCEPROP 0 LASTPIN (-1725 3725) $PN FB34
J 0
(-1715 3735);
DISPLAY 0.680851 (-1715 3735);
PAINT MONO (-1715 3735);
FORCEPROP 0 LASTPIN (-1725 3675) $PN FC19
J 0
(-1715 3685);
DISPLAY 0.680851 (-1715 3685);
PAINT MONO (-1715 3685);
FORCEPROP 0 LASTPIN (-1725 3625) $PN FC23
J 0
(-1715 3635);
DISPLAY 0.680851 (-1715 3635);
PAINT MONO (-1715 3635);
FORCEPROP 0 LASTPIN (-1725 3575) $PN FC25
J 0
(-1715 3585);
DISPLAY 0.680851 (-1715 3585);
PAINT MONO (-1715 3585);
FORCEPROP 0 LASTPIN (-1725 3525) $PN FC28
J 0
(-1715 3535);
DISPLAY 0.680851 (-1715 3535);
PAINT MONO (-1715 3535);
FORCEPROP 0 LASTPIN (-1725 3475) $PN FC3
J 0
(-1715 3485);
DISPLAY 0.680851 (-1715 3485);
PAINT MONO (-1715 3485);
FORCEPROP 0 LASTPIN (-1725 3425) $PN FC6
J 0
(-1715 3435);
DISPLAY 0.680851 (-1715 3435);
PAINT MONO (-1715 3435);
FORCEPROP 0 LASTPIN (-1725 3375) $PN FC9
J 0
(-1715 3385);
DISPLAY 0.680851 (-1715 3385);
PAINT MONO (-1715 3385);
FORCEPROP 0 LASTPIN (-1725 3325) $PN FD1
J 0
(-1715 3335);
DISPLAY 0.680851 (-1715 3335);
PAINT MONO (-1715 3335);
FORCEPROP 0 LASTPIN (-1725 3275) $PN FD35
J 0
(-1715 3285);
DISPLAY 0.680851 (-1715 3285);
PAINT MONO (-1715 3285);
FORCEPROP 0 LASTPIN (-1725 3225) $PN FF14
J 0
(-1715 3235);
DISPLAY 0.680851 (-1715 3235);
PAINT MONO (-1715 3235);
FORCEPROP 0 LASTPIN (-1725 3175) $PN FF21
J 0
(-1715 3185);
DISPLAY 0.680851 (-1715 3185);
PAINT MONO (-1715 3185);
FORCEPROP 0 LASTPIN (-1725 3125) $PN FJ12
J 0
(-1715 3135);
DISPLAY 0.680851 (-1715 3135);
PAINT MONO (-1715 3135);
FORCEPROP 0 LASTPIN (-1725 3075) $PN FJ19
J 0
(-1715 3085);
DISPLAY 0.680851 (-1715 3085);
PAINT MONO (-1715 3085);
FORCEPROP 0 LASTPIN (-1725 3025) $PN H12
J 0
(-1715 3035);
DISPLAY 0.680851 (-1715 3035);
PAINT MONO (-1715 3035);
FORCEPROP 0 LASTPIN (-1725 2975) $PN H16
J 0
(-1715 2985);
DISPLAY 0.680851 (-1715 2985);
PAINT MONO (-1715 2985);
FORCEPROP 0 LASTPIN (-1725 2925) $PN H19
J 0
(-1715 2935);
DISPLAY 0.680851 (-1715 2935);
PAINT MONO (-1715 2935);
FORCEPROP 0 LASTPIN (-1725 2875) $PN H31
J 0
(-1715 2885);
DISPLAY 0.680851 (-1715 2885);
PAINT MONO (-1715 2885);
FORCEPROP 0 LASTPIN (-1725 2825) $PN J22
J 0
(-1715 2835);
DISPLAY 0.680851 (-1715 2835);
PAINT MONO (-1715 2835);
FORCEPROP 0 LASTPIN (-1725 2775) $PN J4
J 0
(-1715 2785);
DISPLAY 0.680851 (-1715 2785);
PAINT MONO (-1715 2785);
FORCEPROP 0 LASTPIN (-1725 2725) $PN K2
J 0
(-1715 2735);
DISPLAY 0.680851 (-1715 2735);
PAINT MONO (-1715 2735);
FORCEPROP 0 LASTPIN (-1725 2675) $PN K34
J 0
(-1715 2685);
DISPLAY 0.680851 (-1715 2685);
PAINT MONO (-1715 2685);
FORCEPROP 0 LASTPIN (-1725 2625) $PN L1
J 0
(-1715 2635);
DISPLAY 0.680851 (-1715 2635);
PAINT MONO (-1715 2635);
FORCEPROP 0 LASTPIN (-1725 2575) $PN L35
J 0
(-1715 2585);
DISPLAY 0.680851 (-1715 2585);
PAINT MONO (-1715 2585);
FORCEPROP 0 LASTPIN (-1725 2525) $PN T13
J 0
(-1715 2535);
DISPLAY 0.680851 (-1715 2535);
PAINT MONO (-1715 2535);
FORCEPROP 0 LASTPIN (-1725 2475) $PN T22
J 0
(-1715 2485);
DISPLAY 0.680851 (-1715 2485);
PAINT MONO (-1715 2485);
FORCEPROP 0 LASTPIN (-1725 2425) $PN T32
J 0
(-1715 2435);
DISPLAY 0.680851 (-1715 2435);
PAINT MONO (-1715 2435);
FORCEPROP 0 LASTPIN (-1725 2375) $PN T4
J 0
(-1715 2385);
DISPLAY 0.680851 (-1715 2385);
PAINT MONO (-1715 2385);
FORCEPROP 0 LASTPIN (-1725 2325) $PN U2
J 0
(-1715 2335);
DISPLAY 0.680851 (-1715 2335);
PAINT MONO (-1715 2335);
FORCEPROP 0 LASTPIN (-1725 2275) $PN U34
J 0
(-1715 2285);
DISPLAY 0.680851 (-1715 2285);
PAINT MONO (-1715 2285);
FORCEPROP 0 LASTPIN (-1725 2225) $PN V1
J 0
(-1715 2235);
DISPLAY 0.680851 (-1715 2235);
PAINT MONO (-1715 2235);
FORCEPROP 0 LASTPIN (-1725 2175) $PN V35
J 0
(-1715 2185);
DISPLAY 0.680851 (-1715 2185);
PAINT MONO (-1715 2185);
FORCEPROP 0 LASTPIN (-1725 2075) $PN A1
J 0
(-1715 2085);
DISPLAY 0.680851 (-1715 2085);
PAINT MONO (-1715 2085);
FORCEPROP 0 LASTPIN (-1725 2025) $PN A35
J 0
(-1715 2035);
DISPLAY 0.680851 (-1715 2035);
PAINT MONO (-1715 2035);
FORCEPROP 0 LASTPIN (-1725 1975) $PN C2
J 0
(-1715 1985);
DISPLAY 0.680851 (-1715 1985);
PAINT MONO (-1715 1985);
FORCEPROP 0 LASTPIN (-1725 1925) $PN C34
J 0
(-1715 1935);
DISPLAY 0.680851 (-1715 1935);
PAINT MONO (-1715 1935);
FORCEPROP 0 LASTPIN (-1725 1875) $PN D1
J 0
(-1715 1885);
DISPLAY 0.680851 (-1715 1885);
PAINT MONO (-1715 1885);
FORCEPROP 0 LASTPIN (-1725 1825) $PN D35
J 0
(-1715 1835);
DISPLAY 0.680851 (-1715 1835);
PAINT MONO (-1715 1835);
FORCEPROP 0 LASTPIN (-1725 1775) $PN FE2
J 0
(-1715 1785);
DISPLAY 0.680851 (-1715 1785);
PAINT MONO (-1715 1785);
FORCEPROP 0 LASTPIN (-1725 1725) $PN FE34
J 0
(-1715 1735);
DISPLAY 0.680851 (-1715 1735);
PAINT MONO (-1715 1735);
FORCEPROP 0 LASTPIN (-1725 1675) $PN FG1
J 0
(-1715 1685);
DISPLAY 0.680851 (-1715 1685);
PAINT MONO (-1715 1685);
FORCEPROP 0 LASTPIN (-1725 1625) $PN FG35
J 0
(-1715 1635);
DISPLAY 0.680851 (-1715 1635);
PAINT MONO (-1715 1635);
FORCEPROP 0 LASTPIN (-1725 1575) $PN FH2
J 0
(-1715 1585);
DISPLAY 0.680851 (-1715 1585);
PAINT MONO (-1715 1585);
FORCEPROP 0 LASTPIN (-1725 1525) $PN FH34
J 0
(-1715 1535);
DISPLAY 0.680851 (-1715 1535);
PAINT MONO (-1715 1535);
FORCEPROP 2 LAST PART_TYPE SMLF
J 0
(-2525 6000);
DISPLAY 0.680851 (-2525 6000);
FORCEPROP 1 LAST MATERIAL IC
J 0
(-2525 5750);
DISPLAY 0.723404 (-2525 5750);
PAINT GREEN (-2525 5750);
FORCEPROP 2 LAST VALUE PT5161LRS
J 0
(-2525 5950);
DISPLAY 0.680851 (-2525 5950);
FORCEPROP 1 LAST NEEDS_NO_SIZE TRUE
J 0
(-2175 3575);
DISPLAY 0.723404 (-2175 3575);
PAINT GREEN (-2175 3575);
DISPLAY INVISIBLE (-2175 3575);
FORCEPROP 1 LAST CDS_LMAN_SYM_OUTLINE -350,2150,300,-2150
J 0
(-2175 3575);
DISPLAY 0.468085 (-2175 3575);
PAINT GREEN (-2175 3575);
DISPLAY INVISIBLE (-2175 3575);
FORCEPROP 2 LAST CDS_LIB pure_quanta
J 0
(-2175 3575);
DISPLAY INVISIBLE (-2175 3575);
FORCEPROP 1 LAST PATH I17
J 0
(-2175 3575);
DISPLAY 0.723404 (-2175 3575);
PAINT GREEN (-2175 3575);
DISPLAY INVISIBLE (-2175 3575);
FORCEPROP 1 LAST PART_NUMBER AJ051610U03
J 0
(-2525 5825);
DISPLAY 0.723404 (-2525 5825);
PAINT GREEN (-2525 5825);
DISPLAY INVISIBLE (-2525 5825);
FORCEADD Q_RES..2
(-7400 3350);
FORCEPROP 1 LAST LOCATION R6809
J 0
(-7355 3475);
DISPLAY 0.978723 (-7355 3475);
PAINT WHITE (-7355 3475);
FORCEPROP 0 LAST $SEC 1
J 0
(-7350 3525);
DISPLAY 0.680851 (-7350 3525);
PAINT MONO (-7350 3525);
DISPLAY INVISIBLE (-7350 3525);
FORCEPROP 0 LAST CDS_SEC 1
J 0
(-7350 3525);
DISPLAY 0.680851 (-7350 3525);
DISPLAY INVISIBLE (-7350 3525);
FORCEPROP 1 LASTPIN (-7400 3450) $PN 1
J 0
(-7395 3412);
DISPLAY 0.787234 (-7395 3412);
PAINT MONO (-7395 3412);
FORCEPROP 1 LASTPIN (-7400 3250) $PN 2
J 0
(-7395 3260);
DISPLAY 0.787234 (-7395 3260);
PAINT MONO (-7395 3260);
FORCEPROP 1 LAST MATERIAL CHIP
J 0
(-7360 3275);
DISPLAY 0.978723 (-7360 3275);
FORCEPROP 1 LAST PACK_TYPE 0201LF
J 0
(-7360 3175);
DISPLAY 0.978723 (-7360 3175);
FORCEPROP 1 LAST WATTAGE 1/20W
J 0
(-7360 3325);
DISPLAY 0.978723 (-7360 3325);
FORCEPROP 1 LAST VALUE 200
J 0
(-7355 3425);
DISPLAY 0.978723 (-7355 3425);
FORCEPROP 1 LAST TOLERANCE 1%
J 0
(-7355 3375);
DISPLAY 0.978723 (-7355 3375);
FORCEPROP 2 LAST CDS_LIB pure_quanta
J 0
(-7400 3350);
DISPLAY INVISIBLE (-7400 3350);
FORCEPROP 1 LAST PATH I18
J 0
(-7350 3525);
DISPLAY 0.978723 (-7350 3525);
PAINT WHITE (-7350 3525);
DISPLAY INVISIBLE (-7350 3525);
FORCEPROP 1 LAST PART_NUMBER CS12001FE12
J 0
(-7360 3225);
DISPLAY 0.978723 (-7360 3225);
DISPLAY INVISIBLE (-7360 3225);
FORCEADD Q_RES..2
(-8425 3900);
FORCEPROP 1 LAST LOCATION R6808
J 0
(-8380 4025);
DISPLAY 0.787234 (-8380 4025);
PAINT SKYBLUE (-8380 4025);
FORCEPROP 0 LAST $SEC 1
J 0
(-8375 4075);
DISPLAY 0.680851 (-8375 4075);
PAINT MONO (-8375 4075);
DISPLAY INVISIBLE (-8375 4075);
FORCEPROP 0 LAST CDS_SEC 1
J 0
(-8375 4075);
DISPLAY 0.680851 (-8375 4075);
DISPLAY INVISIBLE (-8375 4075);
FORCEPROP 1 LASTPIN (-8425 4000) $PN 1
J 0
(-8420 3962);
DISPLAY 0.787234 (-8420 3962);
PAINT MONO (-8420 3962);
FORCEPROP 1 LASTPIN (-8425 3800) $PN 2
J 0
(-8420 3810);
DISPLAY 0.787234 (-8420 3810);
PAINT MONO (-8420 3810);
FORCEPROP 1 LAST PACK_TYPE 0201LF
J 0
(-8385 3725);
DISPLAY 0.787234 (-8385 3725);
FORCEPROP 1 LAST TOLERANCE 1%
J 0
(-8380 3925);
DISPLAY 0.787234 (-8380 3925);
FORCEPROP 1 LAST VALUE 1K
J 0
(-8380 3975);
DISPLAY 0.787234 (-8380 3975);
FORCEPROP 1 LAST WATTAGE 1/20W
J 0
(-8385 3875);
DISPLAY 0.787234 (-8385 3875);
FORCEPROP 1 LAST MATERIAL EMPTY
J 0
(-8385 3825);
DISPLAY 0.787234 (-8385 3825);
PAINT RED (-8385 3825);
FORCEPROP 2 LAST CDS_LIB pure_quanta
J 0
(-8425 3900);
DISPLAY INVISIBLE (-8425 3900);
FORCEPROP 1 LAST PATH I19
J 0
(-8375 4075);
DISPLAY 0.978723 (-8375 4075);
PAINT WHITE (-8375 4075);
DISPLAY INVISIBLE (-8375 4075);
FORCEPROP 1 LAST PART_NUMBER CS21001FE07
J 0
(-8385 3775);
DISPLAY 0.978723 (-8385 3775);
DISPLAY INVISIBLE (-8385 3775);
FORCEADD PT5161LRS..4
(-6250 4150);
FORCEPROP 1 LAST LOCATION U6010
J 0
(-6700 5075);
DISPLAY 0.723404 (-6700 5075);
PAINT SKYBLUE (-6700 5075);
FORCEPROP 0 LAST $SEC 4
J 0
(-6700 5225);
DISPLAY 0.680851 (-6700 5225);
PAINT MONO (-6700 5225);
DISPLAY INVISIBLE (-6700 5225);
FORCEPROP 0 LAST CDS_SEC 4
J 0
(-6700 5225);
DISPLAY 0.680851 (-6700 5225);
DISPLAY INVISIBLE (-6700 5225);
FORCEPROP 0 LASTPIN (-6850 4750) $PN BV20
J 2
(-6860 4760);
DISPLAY 0.680851 (-6860 4760);
PAINT MONO (-6860 4760);
FORCEPROP 0 LASTPIN (-6850 4700) $PN CE17
J 2
(-6860 4710);
DISPLAY 0.680851 (-6860 4710);
PAINT MONO (-6860 4710);
FORCEPROP 0 LASTPIN (-6850 4650) $PN CE20
J 2
(-6860 4660);
DISPLAY 0.680851 (-6860 4660);
PAINT MONO (-6860 4660);
FORCEPROP 0 LASTPIN (-6850 4600) $PN CM17
J 2
(-6860 4610);
DISPLAY 0.680851 (-6860 4610);
PAINT MONO (-6860 4610);
FORCEPROP 0 LASTPIN (-6850 4550) $PN CM20
J 2
(-6860 4560);
DISPLAY 0.680851 (-6860 4560);
PAINT MONO (-6860 4560);
FORCEPROP 0 LASTPIN (-6850 4100) $PN BV17
J 2
(-6860 4110);
DISPLAY 0.680851 (-6860 4110);
PAINT MONO (-6860 4110);
FORCEPROP 0 LASTPIN (-5700 4750) $PN AC17
J 0
(-5690 4760);
DISPLAY 0.680851 (-5690 4760);
PAINT MONO (-5690 4760);
FORCEPROP 0 LASTPIN (-5700 4700) $PN AC20
J 0
(-5690 4710);
DISPLAY 0.680851 (-5690 4710);
PAINT MONO (-5690 4710);
FORCEPROP 0 LASTPIN (-5700 4650) $PN AK17
J 0
(-5690 4660);
DISPLAY 0.680851 (-5690 4660);
PAINT MONO (-5690 4660);
FORCEPROP 0 LASTPIN (-5700 4600) $PN AK20
J 0
(-5690 4610);
DISPLAY 0.680851 (-5690 4610);
PAINT MONO (-5690 4610);
FORCEPROP 0 LASTPIN (-5700 4550) $PN AU17
J 0
(-5690 4560);
DISPLAY 0.680851 (-5690 4560);
PAINT MONO (-5690 4560);
FORCEPROP 0 LASTPIN (-5700 4500) $PN AU20
J 0
(-5690 4510);
DISPLAY 0.680851 (-5690 4510);
PAINT MONO (-5690 4510);
FORCEPROP 0 LASTPIN (-5700 4450) $PN BD17
J 0
(-5690 4460);
DISPLAY 0.680851 (-5690 4460);
PAINT MONO (-5690 4460);
FORCEPROP 0 LASTPIN (-5700 4400) $PN BD20
J 0
(-5690 4410);
DISPLAY 0.680851 (-5690 4410);
PAINT MONO (-5690 4410);
FORCEPROP 0 LASTPIN (-5700 4350) $PN DF17
J 0
(-5690 4360);
DISPLAY 0.680851 (-5690 4360);
PAINT MONO (-5690 4360);
FORCEPROP 0 LASTPIN (-5700 4300) $PN DF20
J 0
(-5690 4310);
DISPLAY 0.680851 (-5690 4310);
PAINT MONO (-5690 4310);
FORCEPROP 0 LASTPIN (-5700 4250) $PN DN17
J 0
(-5690 4260);
DISPLAY 0.680851 (-5690 4260);
PAINT MONO (-5690 4260);
FORCEPROP 0 LASTPIN (-5700 4200) $PN DN20
J 0
(-5690 4210);
DISPLAY 0.680851 (-5690 4210);
PAINT MONO (-5690 4210);
FORCEPROP 0 LASTPIN (-5700 4150) $PN DY17
J 0
(-5690 4160);
DISPLAY 0.680851 (-5690 4160);
PAINT MONO (-5690 4160);
FORCEPROP 0 LASTPIN (-5700 4100) $PN DY20
J 0
(-5690 4110);
DISPLAY 0.680851 (-5690 4110);
PAINT MONO (-5690 4110);
FORCEPROP 0 LASTPIN (-5700 4050) $PN EG17
J 0
(-5690 4060);
DISPLAY 0.680851 (-5690 4060);
PAINT MONO (-5690 4060);
FORCEPROP 0 LASTPIN (-5700 4000) $PN EG20
J 0
(-5690 4010);
DISPLAY 0.680851 (-5690 4010);
PAINT MONO (-5690 4010);
FORCEPROP 0 LASTPIN (-5700 3950) $PN EP17
J 0
(-5690 3960);
DISPLAY 0.680851 (-5690 3960);
PAINT MONO (-5690 3960);
FORCEPROP 0 LASTPIN (-5700 3900) $PN EP20
J 0
(-5690 3910);
DISPLAY 0.680851 (-5690 3910);
PAINT MONO (-5690 3910);
FORCEPROP 0 LASTPIN (-5700 3850) $PN T17
J 0
(-5690 3860);
DISPLAY 0.680851 (-5690 3860);
PAINT MONO (-5690 3860);
FORCEPROP 0 LASTPIN (-5700 3800) $PN T20
J 0
(-5690 3810);
DISPLAY 0.680851 (-5690 3810);
PAINT MONO (-5690 3810);
FORCEPROP 0 LASTPIN (-5700 3650) $PN BL17
J 0
(-5690 3660);
DISPLAY 0.680851 (-5690 3660);
PAINT MONO (-5690 3660);
FORCEPROP 0 LASTPIN (-5700 3600) $PN BL20
J 0
(-5690 3610);
DISPLAY 0.680851 (-5690 3610);
PAINT MONO (-5690 3610);
FORCEPROP 0 LASTPIN (-5700 3550) $PN CW17
J 0
(-5690 3560);
DISPLAY 0.680851 (-5690 3560);
PAINT MONO (-5690 3560);
FORCEPROP 0 LASTPIN (-5700 3500) $PN CW20
J 0
(-5690 3510);
DISPLAY 0.680851 (-5690 3510);
PAINT MONO (-5690 3510);
FORCEPROP 0 LASTPIN (-6850 3650) $PN G1
J 2
(-6860 3660);
DISPLAY 0.680851 (-6860 3660);
PAINT MONO (-6860 3660);
FORCEPROP 2 LAST PART_TYPE SMLF
J 0
(-6700 5175);
DISPLAY 0.680851 (-6700 5175);
FORCEPROP 2 LAST VALUE PT5161LRS
J 0
(-6700 5125);
DISPLAY 0.680851 (-6700 5125);
FORCEPROP 1 LAST MATERIAL IC
J 0
(-6700 4925);
DISPLAY 0.723404 (-6700 4925);
PAINT GREEN (-6700 4925);
FORCEPROP 1 LAST NEEDS_NO_SIZE TRUE
J 0
(-6250 4150);
DISPLAY 0.723404 (-6250 4150);
PAINT GREEN (-6250 4150);
DISPLAY INVISIBLE (-6250 4150);
FORCEPROP 1 LAST CDS_LMAN_SYM_OUTLINE -450,750,400,-750
J 0
(-6250 4150);
DISPLAY 0.468085 (-6250 4150);
PAINT GREEN (-6250 4150);
DISPLAY INVISIBLE (-6250 4150);
FORCEPROP 2 LAST CDS_LIB pure_quanta
J 0
(-6250 4150);
DISPLAY INVISIBLE (-6250 4150);
FORCEPROP 1 LAST PATH I3
J 0
(-6250 4150);
DISPLAY 0.723404 (-6250 4150);
PAINT GREEN (-6250 4150);
DISPLAY INVISIBLE (-6250 4150);
FORCEPROP 1 LAST PART_NUMBER AJ051610U03
J 0
(-6700 5000);
DISPLAY 0.723404 (-6700 5000);
PAINT GREEN (-6700 5000);
DISPLAY INVISIBLE (-6700 5000);
FORCEADD P1V0..1
(-8425 4125);
FORCEPROP 3 LASTPIN (-8425 4075) SIG_NAME P1V8_CPU0_RT_1D\g
J 0
(-8415 4085);
DISPLAY 0.659574 (-8415 4085);
PAINT MONO (-8415 4085);
DISPLAY INVISIBLE (-8415 4085);
FORCEPROP 1 LAST HDL_POWER P1V8_CPU0_RT_1D
J 1
(-8425 4175);
DISPLAY 0.489362 (-8425 4175);
PAINT SKYBLUE (-8425 4175);
FORCEPROP 2 LAST CDS_LIB pure_quanta_power
J 0
(-8425 4125);
DISPLAY INVISIBLE (-8425 4125);
FORCEPROP 1 LAST PATH I5
J 0
(-8375 4150);
DISPLAY 0.872340 (-8375 4150);
PAINT AQUA (-8375 4150);
DISPLAY INVISIBLE (-8375 4150);
FORCEADD P1V0..1
(-8100 4400);
FORCEPROP 3 LASTPIN (-8100 4350) SIG_NAME P1V8_CPU0_RT0_1A_1D\g
J 0
(-8090 4360);
DISPLAY 0.659574 (-8090 4360);
PAINT MONO (-8090 4360);
DISPLAY INVISIBLE (-8090 4360);
FORCEPROP 1 LAST HDL_POWER P1V8_CPU0_RT0_1A_1D
J 1
(-8100 4450);
DISPLAY 0.489362 (-8100 4450);
PAINT SKYBLUE (-8100 4450);
FORCEPROP 2 LAST CDS_LIB pure_quanta_power
J 0
(-8100 4400);
DISPLAY INVISIBLE (-8100 4400);
FORCEPROP 1 LAST PATH I6
J 0
(-8050 4425);
DISPLAY 0.872340 (-8050 4425);
PAINT AQUA (-8050 4425);
DISPLAY INVISIBLE (-8050 4425);
FORCEADD P1V0..1
(-7525 4850);
FORCEPROP 3 LASTPIN (-7525 4800) SIG_NAME P1V8_CPU0_RT0_1A\g
J 0
(-7515 4810);
DISPLAY 0.659574 (-7515 4810);
PAINT MONO (-7515 4810);
DISPLAY INVISIBLE (-7515 4810);
FORCEPROP 1 LAST HDL_POWER P1V8_CPU0_RT0_1A
J 1
(-7525 4900);
DISPLAY 0.489362 (-7525 4900);
PAINT SKYBLUE (-7525 4900);
FORCEPROP 2 LAST CDS_LIB pure_quanta_power
J 0
(-7525 4850);
DISPLAY INVISIBLE (-7525 4850);
FORCEPROP 1 LAST PATH I7
J 0
(-7475 4875);
DISPLAY 0.872340 (-7475 4875);
PAINT AQUA (-7475 4875);
DISPLAY INVISIBLE (-7475 4875);
FORCEADD VCC_CORE..1
(-5000 4550);
FORCEPROP 3 LASTPIN (-5000 4500) SIG_NAME P0V9_CPU0_RT0_2A_2D\g
J 0
(-4990 4510);
DISPLAY 0.659574 (-4990 4510);
PAINT MONO (-4990 4510);
DISPLAY INVISIBLE (-4990 4510);
FORCEPROP 1 LAST HDL_POWER P0V9_CPU0_RT0_2A_2D
J 1
(-5000 4600);
DISPLAY 0.617021 (-5000 4600);
PAINT SKYBLUE (-5000 4600);
FORCEPROP 2 LAST CDS_LIB pure_quanta_power
J 0
(-5000 4550);
DISPLAY INVISIBLE (-5000 4550);
FORCEPROP 1 LAST PATH I8
J 0
(-4950 4575);
DISPLAY 0.872340 (-4950 4575);
PAINT AQUA (-4950 4575);
DISPLAY INVISIBLE (-4950 4575);
FORCEADD VCC_CORE..1
(-4425 5025);
FORCEPROP 3 LASTPIN (-4425 4975) SIG_NAME P0V9_CPU0_RT0_2A\g
J 0
(-4415 4985);
DISPLAY 0.659574 (-4415 4985);
PAINT MONO (-4415 4985);
DISPLAY INVISIBLE (-4415 4985);
FORCEPROP 1 LAST HDL_POWER P0V9_CPU0_RT0_2A
J 1
(-4425 5075);
DISPLAY 0.617021 (-4425 5075);
PAINT SKYBLUE (-4425 5075);
FORCEPROP 2 LAST CDS_LIB pure_quanta_power
J 0
(-4425 5025);
DISPLAY INVISIBLE (-4425 5025);
FORCEPROP 1 LAST PATH I9
J 0
(-4375 5050);
DISPLAY 0.872340 (-4375 5050);
PAINT AQUA (-4375 5050);
DISPLAY INVISIBLE (-4375 5050);
FORCEADD QUANTA_TITLE_BLOCK_C..1
(0 0);
FORCEPROP 0 LAST CDS_CON_LAST_MODIFIED Thu Sep 14 16:13:08 2023
J 0
(-1885 15);
DISPLAY INVISIBLE (-1885 15);
FORCEPROP 1 LAST CUSTOM_TXT_CDS <CON_LAST_MODIFIED>
J 0
(-1885 15);
DISPLAY 0.978723 (-1885 15);
FORCEPROP 2 LAST CUSTOM_TXT_CDS <XR_PAGE_TITLE>
J 0
(-7890 5250);
DISPLAY 0.638298 (-7890 5250);
PAINT PINK (-7890 5250);
DISPLAY INVISIBLE (-7890 5250);
FORCEPROP 1 LAST CUSTOM_TXT_CDS <NAME_2>
J 0
(-3175 50);
FORCEPROP 1 LAST CUSTOM_TXT_CDS <NAME_1>
J 0
(-3175 175);
FORCEPROP 1 LAST CUSTOM_TXT_CDS <Q_NUMBER>
J 0
(-1403 103);
DISPLAY 1.212766 (-1403 103);
FORCEPROP 1 LAST CUSTOM_TXT_CDS <Q_PROJ>
J 0
(-2382 102);
DISPLAY 1.212766 (-2382 102);
FORCEPROP 1 LAST CUSTOM_TXT_CDS <Q_REV>
J 0
(-184 103);
DISPLAY 1.212766 (-184 103);
FORCEPROP 1 LAST CUSTOM_TXT_CDS <CON_PAGE_NUM> OF <CON_TOTAL_PAGES>
J 0
(-446 18);
DISPLAY 0.978723 (-446 18);
FORCEPROP 1 LAST Q_TITLE RETIMER_CPU0_P0 POWER(6)
J 0
(-9366 26);
DISPLAY 2.446809 (-9366 26);
PAINT GREEN (-9366 26);
FORCEPROP 2 LAST PAGE_BORDER TRUE
J 0
(-7890 5250);
DISPLAY 0.638298 (-7890 5250);
PAINT PINK (-7890 5250);
DISPLAY INVISIBLE (-7890 5250);
FORCEPROP 1 LAST CDS_LMAN_SYM_OUTLINE -9475,6775,100,-125
J 0
(0 0);
DISPLAY 0.468085 (0 0);
PAINT GREEN (0 0);
DISPLAY INVISIBLE (0 0);
FORCEPROP 2 LAST CDS_LIB pure_quanta
J 0
(0 0);
DISPLAY INVISIBLE (0 0);
FORCEPROP 2 LAST CDS_XR_PAGE_TITLE CR-278 : @T6G_MB_LIB.T6G(SCH_1):PAGE278
J 0
(-7890 5250);
DISPLAY 0.638298 (-7890 5250);
PAINT PINK (-7890 5250);
DISPLAY INVISIBLE (-7890 5250);
FORCEPROP 1 LAST Q_DEPT BU9
J 1
(-3763 49);
DISPLAY 1.957447 (-3763 49);
PAINT GREEN (-3763 49);
DISPLAY INVISIBLE (-3763 49);
FORCEPROP 1 LAST COMMENT_BODY TRUE
J 0
(12 -13);
DISPLAY 0.978723 (12 -13);
PAINT GREEN (12 -13);
DISPLAY INVISIBLE (12 -13);
FORCEADD DNS..2
(-8400 3900);
PAINT RED (-8400 3900);
FORCEPROP 2 LAST CDS_LIB mstr_misc
J 0
(-8400 3900);
DISPLAY INVISIBLE (-8400 3900);
FORCEPROP 1 LAST COMMENT_BODY TRUE
J 0
(-8400 3900);
DISPLAY INVISIBLE (-8400 3900);
WIRE 16 -1 (-7400 3250)(-7400 3150);
WIRE 16 -1 (-1200 1150)(-1200 1000);
WIRE 16 -1 (-1050 1700)(-1050 1550);
WIRE 16 -1 (-8425 4075)(-8425 4000);
WIRE 16 -1 (-6850 3650)(-7400 3650);
WIRE 16 -1 (-7400 3650)(-7400 3450);
WIRE 16 -1 (-7400 3650)(-8425 3650);
FORCEPROP 2 LAST SIG_NAME RT_CPU0_P0_VQPS
J 0
(-7610 3660);
DISPLAY 0.680851 (-7610 3660);
PAINT SKYBLUE (-7610 3660);
FORCEPROP 2 LASTPROP $XRERR UNIQUE?
J 0
(-7850 3660);
DISPLAY 0.638298 (-7850 3660);
PAINT MONO (-7850 3660);
DISPLAY INVISIBLE (-7850 3660);
WIRE 16 -1 (-8425 3800)(-8425 3650);
WIRE 16 -1 (-6850 4100)(-8100 4100);
WIRE 16 -1 (-8100 4350)(-8100 4100);
WIRE 16 -1 (-5375 3600)(-5375 3550);
WIRE 16 -1 (-5375 3650)(-5375 3600);
WIRE 16 -1 (-5700 3600)(-5375 3600);
WIRE 16 -1 (-5375 3550)(-5375 3500);
WIRE 16 -1 (-5700 3550)(-5375 3550);
WIRE 16 -1 (-5375 3500)(-5700 3500);
WIRE 16 -1 (-5375 3650)(-4400 3650);
WIRE 16 -1 (-5700 3650)(-5375 3650);
WIRE 16 -1 (-4400 3750)(-4400 3650);
WIRE 16 -1 (-1200 1625)(-1200 1575);
WIRE 16 -1 (-1200 1675)(-1200 1625);
WIRE 16 -1 (-1200 1625)(-1725 1625);
WIRE 16 -1 (-1200 1575)(-1200 1525);
WIRE 16 -1 (-1200 1575)(-1725 1575);
WIRE 16 -1 (-1200 1525)(-1200 1350);
WIRE 16 -1 (-1200 1525)(-1725 1525);
WIRE 16 -1 (-1200 1725)(-1200 1675);
WIRE 16 -1 (-1200 1675)(-1725 1675);
WIRE 16 -1 (-1200 1775)(-1200 1725);
WIRE 16 -1 (-1200 1725)(-1725 1725);
WIRE 16 -1 (-1200 1825)(-1200 1775);
WIRE 16 -1 (-1200 1775)(-1725 1775);
WIRE 16 -1 (-1200 1875)(-1200 1825);
WIRE 16 -1 (-1200 1825)(-1725 1825);
WIRE 16 -1 (-1200 1925)(-1200 1875);
WIRE 16 -1 (-1200 1875)(-1725 1875);
WIRE 16 -1 (-1200 1975)(-1200 1925);
WIRE 16 -1 (-1200 1925)(-1725 1925);
WIRE 16 -1 (-1200 2025)(-1200 1975);
WIRE 16 -1 (-1200 1975)(-1725 1975);
WIRE 16 -1 (-1200 2025)(-1725 2025);
FORCEPROP 2 LAST SIG_NAME NCF_CPU0_P0_GND
J 0
(-1610 2035);
DISPLAY 0.553191 (-1610 2035);
PAINT SKYBLUE (-1610 2035);
FORCEPROP 2 LASTPROP $XRERR UNIQUE?
J 0
(-1850 2035);
DISPLAY 0.638298 (-1850 2035);
PAINT MONO (-1850 2035);
DISPLAY INVISIBLE (-1850 2035);
WIRE 16 -1 (-2675 1575)(-2875 1575);
WIRE 16 -1 (-2875 1625)(-2875 1575);
WIRE 16 -1 (-2875 1575)(-2875 1525);
WIRE 16 -1 (-2675 1525)(-2875 1525);
WIRE 16 -1 (-2875 1525)(-2875 1375);
WIRE 16 -1 (-2675 1625)(-2875 1625);
WIRE 16 -1 (-2875 1675)(-2875 1625);
WIRE 16 -1 (-2675 1675)(-2875 1675);
WIRE 16 -1 (-2875 1725)(-2875 1675);
WIRE 16 -1 (-2675 1725)(-2875 1725);
WIRE 16 -1 (-2875 1775)(-2875 1725);
WIRE 16 -1 (-2675 1775)(-2875 1775);
WIRE 16 -1 (-2875 1825)(-2875 1775);
WIRE 16 -1 (-2675 1825)(-2875 1825);
WIRE 16 -1 (-2875 1875)(-2875 1825);
WIRE 16 -1 (-2675 1875)(-2875 1875);
WIRE 16 -1 (-2875 1925)(-2875 1875);
WIRE 16 -1 (-2675 1925)(-2875 1925);
WIRE 16 -1 (-2875 1975)(-2875 1925);
WIRE 16 -1 (-2675 1975)(-2875 1975);
WIRE 16 -1 (-2875 2025)(-2875 1975);
WIRE 16 -1 (-2875 2075)(-2875 2025);
WIRE 16 -1 (-2675 2025)(-2875 2025);
WIRE 16 -1 (-2675 2075)(-2875 2075);
WIRE 16 -1 (-2875 2125)(-2875 2075);
WIRE 16 -1 (-2675 2125)(-2875 2125);
WIRE 16 -1 (-2875 2175)(-2875 2125);
WIRE 16 -1 (-2675 2175)(-2875 2175);
WIRE 16 -1 (-2875 2225)(-2875 2175);
WIRE 16 -1 (-2675 2225)(-2875 2225);
WIRE 16 -1 (-2875 2275)(-2875 2225);
WIRE 16 -1 (-2675 2275)(-2875 2275);
WIRE 16 -1 (-2875 2325)(-2875 2275);
WIRE 16 -1 (-2675 2325)(-2875 2325);
WIRE 16 -1 (-2875 2375)(-2875 2325);
WIRE 16 -1 (-2675 2375)(-2875 2375);
WIRE 16 -1 (-2875 2425)(-2875 2375);
WIRE 16 -1 (-2675 2425)(-2875 2425);
WIRE 16 -1 (-2875 2475)(-2875 2425);
WIRE 16 -1 (-2675 2475)(-2875 2475);
WIRE 16 -1 (-2875 2525)(-2875 2475);
WIRE 16 -1 (-2875 2575)(-2875 2525);
WIRE 16 -1 (-2675 2525)(-2875 2525);
WIRE 16 -1 (-2675 2575)(-2875 2575);
WIRE 16 -1 (-2875 2625)(-2875 2575);
WIRE 16 -1 (-2675 2625)(-2875 2625);
WIRE 16 -1 (-2875 2675)(-2875 2625);
WIRE 16 -1 (-2675 2675)(-2875 2675);
WIRE 16 -1 (-2875 2725)(-2875 2675);
WIRE 16 -1 (-2675 2725)(-2875 2725);
WIRE 16 -1 (-2875 2775)(-2875 2725);
WIRE 16 -1 (-2675 2775)(-2875 2775);
WIRE 16 -1 (-2875 2825)(-2875 2775);
WIRE 16 -1 (-2675 2825)(-2875 2825);
WIRE 16 -1 (-2875 2875)(-2875 2825);
WIRE 16 -1 (-2675 2875)(-2875 2875);
WIRE 16 -1 (-2875 2925)(-2875 2875);
WIRE 16 -1 (-2675 2925)(-2875 2925);
WIRE 16 -1 (-2875 2975)(-2875 2925);
WIRE 16 -1 (-2675 2975)(-2875 2975);
WIRE 16 -1 (-2875 3025)(-2875 2975);
WIRE 16 -1 (-2875 3075)(-2875 3025);
WIRE 16 -1 (-2675 3025)(-2875 3025);
WIRE 16 -1 (-2675 3075)(-2875 3075);
WIRE 16 -1 (-2875 3125)(-2875 3075);
WIRE 16 -1 (-2675 3125)(-2875 3125);
WIRE 16 -1 (-2875 3175)(-2875 3125);
WIRE 16 -1 (-2675 3175)(-2875 3175);
WIRE 16 -1 (-2875 3225)(-2875 3175);
WIRE 16 -1 (-2675 3225)(-2875 3225);
WIRE 16 -1 (-2875 3275)(-2875 3225);
WIRE 16 -1 (-2675 3275)(-2875 3275);
WIRE 16 -1 (-2875 3325)(-2875 3275);
WIRE 16 -1 (-2675 3325)(-2875 3325);
WIRE 16 -1 (-2875 3375)(-2875 3325);
WIRE 16 -1 (-2675 3375)(-2875 3375);
WIRE 16 -1 (-2875 3425)(-2875 3375);
WIRE 16 -1 (-2675 3425)(-2875 3425);
WIRE 16 -1 (-2875 3475)(-2875 3425);
WIRE 16 -1 (-2675 3475)(-2875 3475);
WIRE 16 -1 (-2875 3525)(-2875 3475);
WIRE 16 -1 (-2675 3525)(-2875 3525);
WIRE 16 -1 (-2875 3575)(-2875 3525);
WIRE 16 -1 (-2875 3625)(-2875 3575);
WIRE 16 -1 (-2675 3575)(-2875 3575);
WIRE 16 -1 (-2675 3625)(-2875 3625);
WIRE 16 -1 (-2875 3675)(-2875 3625);
WIRE 16 -1 (-2675 3675)(-2875 3675);
WIRE 16 -1 (-2875 3725)(-2875 3675);
WIRE 16 -1 (-2675 3725)(-2875 3725);
WIRE 16 -1 (-2875 3775)(-2875 3725);
WIRE 16 -1 (-2675 3775)(-2875 3775);
WIRE 16 -1 (-2875 3825)(-2875 3775);
WIRE 16 -1 (-2675 3825)(-2875 3825);
WIRE 16 -1 (-2875 3875)(-2875 3825);
WIRE 16 -1 (-2675 3875)(-2875 3875);
WIRE 16 -1 (-2875 3925)(-2875 3875);
WIRE 16 -1 (-2675 3925)(-2875 3925);
WIRE 16 -1 (-2875 3975)(-2875 3925);
WIRE 16 -1 (-2675 3975)(-2875 3975);
WIRE 16 -1 (-2875 4025)(-2875 3975);
WIRE 16 -1 (-2675 4025)(-2875 4025);
WIRE 16 -1 (-2875 4075)(-2875 4025);
WIRE 16 -1 (-2875 4125)(-2875 4075);
WIRE 16 -1 (-2675 4075)(-2875 4075);
WIRE 16 -1 (-2675 4125)(-2875 4125);
WIRE 16 -1 (-2875 4175)(-2875 4125);
WIRE 16 -1 (-2675 4175)(-2875 4175);
WIRE 16 -1 (-2875 4225)(-2875 4175);
WIRE 16 -1 (-2675 4225)(-2875 4225);
WIRE 16 -1 (-2875 4275)(-2875 4225);
WIRE 16 -1 (-2675 4275)(-2875 4275);
WIRE 16 -1 (-2875 4325)(-2875 4275);
WIRE 16 -1 (-2675 4325)(-2875 4325);
WIRE 16 -1 (-2875 4375)(-2875 4325);
WIRE 16 -1 (-2675 4375)(-2875 4375);
WIRE 16 -1 (-2875 4425)(-2875 4375);
WIRE 16 -1 (-2675 4425)(-2875 4425);
WIRE 16 -1 (-2875 4475)(-2875 4425);
WIRE 16 -1 (-2675 4475)(-2875 4475);
WIRE 16 -1 (-2875 4525)(-2875 4475);
WIRE 16 -1 (-2675 4525)(-2875 4525);
WIRE 16 -1 (-2875 4575)(-2875 4525);
WIRE 16 -1 (-2875 4625)(-2875 4575);
WIRE 16 -1 (-2675 4575)(-2875 4575);
WIRE 16 -1 (-2675 4625)(-2875 4625);
WIRE 16 -1 (-2875 4675)(-2875 4625);
WIRE 16 -1 (-2675 4675)(-2875 4675);
WIRE 16 -1 (-2875 4725)(-2875 4675);
WIRE 16 -1 (-2675 4725)(-2875 4725);
WIRE 16 -1 (-2875 4775)(-2875 4725);
WIRE 16 -1 (-2675 4775)(-2875 4775);
WIRE 16 -1 (-2875 4825)(-2875 4775);
WIRE 16 -1 (-2675 4825)(-2875 4825);
WIRE 16 -1 (-2875 4875)(-2875 4825);
WIRE 16 -1 (-2675 4875)(-2875 4875);
WIRE 16 -1 (-2875 4925)(-2875 4875);
WIRE 16 -1 (-2675 4925)(-2875 4925);
WIRE 16 -1 (-2875 4975)(-2875 4925);
WIRE 16 -1 (-2675 4975)(-2875 4975);
WIRE 16 -1 (-2875 5025)(-2875 4975);
WIRE 16 -1 (-2675 5025)(-2875 5025);
WIRE 16 -1 (-2875 5075)(-2875 5025);
WIRE 16 -1 (-2875 5125)(-2875 5075);
WIRE 16 -1 (-2675 5075)(-2875 5075);
WIRE 16 -1 (-2675 5125)(-2875 5125);
WIRE 16 -1 (-2875 5175)(-2875 5125);
WIRE 16 -1 (-2675 5175)(-2875 5175);
WIRE 16 -1 (-2875 5225)(-2875 5175);
WIRE 16 -1 (-2675 5225)(-2875 5225);
WIRE 16 -1 (-2875 5275)(-2875 5225);
WIRE 16 -1 (-2675 5275)(-2875 5275);
WIRE 16 -1 (-2875 5325)(-2875 5275);
WIRE 16 -1 (-2675 5325)(-2875 5325);
WIRE 16 -1 (-2875 5375)(-2875 5325);
WIRE 16 -1 (-2675 5375)(-2875 5375);
WIRE 16 -1 (-2875 5425)(-2875 5375);
WIRE 16 -1 (-2675 5425)(-2875 5425);
WIRE 16 -1 (-2875 5475)(-2875 5425);
WIRE 16 -1 (-2675 5475)(-2875 5475);
WIRE 16 -1 (-2875 5525)(-2875 5475);
WIRE 16 -1 (-2675 5525)(-2875 5525);
WIRE 16 -1 (-2875 5575)(-2875 5525);
WIRE 16 -1 (-2675 5575)(-2875 5575);
WIRE 16 -1 (-5475 4550)(-5475 4500);
WIRE 16 -1 (-5475 4600)(-5475 4550);
WIRE 16 -1 (-5700 4550)(-5475 4550);
WIRE 16 -1 (-5475 4500)(-5700 4500);
WIRE 16 -1 (-5475 4650)(-5475 4600);
WIRE 16 -1 (-5700 4600)(-5475 4600);
WIRE 16 -1 (-5475 4700)(-5475 4650);
WIRE 16 -1 (-5700 4650)(-5475 4650);
WIRE 16 -1 (-5475 4750)(-5475 4700);
WIRE 16 -1 (-5700 4700)(-5475 4700);
WIRE 16 -1 (-5475 4750)(-4425 4750);
WIRE 16 -1 (-5700 4750)(-5475 4750);
WIRE 16 -1 (-4425 4750)(-4425 4250);
WIRE 16 -1 (-4425 4750)(-4425 4975);
WIRE 16 -1 (-5450 4250)(-4425 4250);
WIRE 16 -1 (-5450 4250)(-5450 4200);
WIRE 16 -1 (-5450 4250)(-5700 4250);
WIRE 16 -1 (-5450 4200)(-5450 4150);
WIRE 16 -1 (-5700 4200)(-5450 4200);
WIRE 16 -1 (-5450 4150)(-5450 4100);
WIRE 16 -1 (-5700 4150)(-5450 4150);
WIRE 16 -1 (-5700 4100)(-5450 4100);
WIRE 16 -1 (-5450 4100)(-5450 4050);
WIRE 16 -1 (-5450 4050)(-5450 4000);
WIRE 16 -1 (-5700 4050)(-5450 4050);
WIRE 16 -1 (-5450 4000)(-5450 3950);
WIRE 16 -1 (-5700 4000)(-5450 4000);
WIRE 16 -1 (-5450 3950)(-5450 3900);
WIRE 16 -1 (-5700 3950)(-5450 3950);
WIRE 16 -1 (-5450 3900)(-5450 3850);
WIRE 16 -1 (-5700 3900)(-5450 3900);
WIRE 16 -1 (-5450 3850)(-5450 3800);
WIRE 16 -1 (-5700 3850)(-5450 3850);
WIRE 16 -1 (-5450 3800)(-5700 3800);
WIRE 16 -1 (-1525 5575)(-1525 5525);
WIRE 16 -1 (-1525 5575)(-1725 5575);
WIRE 16 -1 (-1525 5525)(-1525 5475);
WIRE 16 -1 (-1525 5525)(-1725 5525);
WIRE 16 -1 (-1525 5475)(-1525 5425);
WIRE 16 -1 (-1525 5475)(-1725 5475);
WIRE 16 -1 (-1525 5425)(-1525 5375);
WIRE 16 -1 (-1525 5425)(-1725 5425);
WIRE 16 -1 (-1525 5375)(-1525 5325);
WIRE 16 -1 (-1525 5375)(-1725 5375);
WIRE 16 -1 (-1525 5325)(-1525 5275);
WIRE 16 -1 (-1525 5325)(-1725 5325);
WIRE 16 -1 (-1525 5275)(-1525 5225);
WIRE 16 -1 (-1525 5275)(-1725 5275);
WIRE 16 -1 (-1525 5225)(-1525 5175);
WIRE 16 -1 (-1525 5225)(-1725 5225);
WIRE 16 -1 (-1525 5175)(-1525 5125);
WIRE 16 -1 (-1525 5175)(-1725 5175);
WIRE 16 -1 (-1525 5125)(-1725 5125);
WIRE 16 -1 (-1525 5125)(-1525 5075);
WIRE 16 -1 (-1525 5075)(-1525 5025);
WIRE 16 -1 (-1525 5075)(-1725 5075);
WIRE 16 -1 (-1525 5025)(-1525 4975);
WIRE 16 -1 (-1525 5025)(-1725 5025);
WIRE 16 -1 (-1525 4975)(-1525 4925);
WIRE 16 -1 (-1525 4975)(-1725 4975);
WIRE 16 -1 (-1525 4925)(-1525 4875);
WIRE 16 -1 (-1525 4925)(-1725 4925);
WIRE 16 -1 (-1525 4875)(-1525 4825);
WIRE 16 -1 (-1525 4875)(-1725 4875);
WIRE 16 -1 (-1525 4825)(-1525 4775);
WIRE 16 -1 (-1525 4825)(-1725 4825);
WIRE 16 -1 (-1525 4775)(-1525 4725);
WIRE 16 -1 (-1525 4775)(-1725 4775);
WIRE 16 -1 (-1525 4725)(-1525 4675);
WIRE 16 -1 (-1525 4725)(-1725 4725);
WIRE 16 -1 (-1525 4675)(-1525 4625);
WIRE 16 -1 (-1525 4675)(-1725 4675);
WIRE 16 -1 (-1525 4625)(-1525 4575);
WIRE 16 -1 (-1525 4625)(-1725 4625);
WIRE 16 -1 (-1525 4575)(-1525 4525);
WIRE 16 -1 (-1525 4575)(-1725 4575);
WIRE 16 -1 (-1525 4525)(-1525 4475);
WIRE 16 -1 (-1525 4525)(-1725 4525);
WIRE 16 -1 (-1525 4475)(-1525 4425);
WIRE 16 -1 (-1525 4475)(-1725 4475);
WIRE 16 -1 (-1525 4425)(-1525 4375);
WIRE 16 -1 (-1525 4425)(-1725 4425);
WIRE 16 -1 (-1525 4375)(-1525 4325);
WIRE 16 -1 (-1525 4375)(-1725 4375);
WIRE 16 -1 (-1525 4325)(-1525 4275);
WIRE 16 -1 (-1525 4325)(-1725 4325);
WIRE 16 -1 (-1525 4275)(-1525 4225);
WIRE 16 -1 (-1525 4275)(-1725 4275);
WIRE 16 -1 (-1525 4225)(-1525 4175);
WIRE 16 -1 (-1525 4225)(-1725 4225);
WIRE 16 -1 (-1525 4175)(-1525 4125);
WIRE 16 -1 (-1525 4175)(-1725 4175);
WIRE 16 -1 (-1525 4125)(-1725 4125);
WIRE 16 -1 (-1525 4125)(-1525 4075);
WIRE 16 -1 (-1525 4075)(-1525 4025);
WIRE 16 -1 (-1525 4075)(-1725 4075);
WIRE 16 -1 (-1525 4025)(-1525 3975);
WIRE 16 -1 (-1525 4025)(-1725 4025);
WIRE 16 -1 (-1525 3975)(-1525 3925);
WIRE 16 -1 (-1525 3975)(-1725 3975);
WIRE 16 -1 (-1525 3925)(-1525 3875);
WIRE 16 -1 (-1525 3925)(-1725 3925);
WIRE 16 -1 (-1525 3875)(-1525 3825);
WIRE 16 -1 (-1525 3875)(-1725 3875);
WIRE 16 -1 (-1525 3825)(-1525 3775);
WIRE 16 -1 (-1525 3825)(-1725 3825);
WIRE 16 -1 (-1525 3775)(-1525 3725);
WIRE 16 -1 (-1525 3775)(-1725 3775);
WIRE 16 -1 (-1525 3725)(-1525 3675);
WIRE 16 -1 (-1525 3725)(-1725 3725);
WIRE 16 -1 (-1525 3675)(-1525 3625);
WIRE 16 -1 (-1525 3675)(-1725 3675);
WIRE 16 -1 (-1525 3625)(-1525 3575);
WIRE 16 -1 (-1525 3625)(-1725 3625);
WIRE 16 -1 (-1525 3575)(-1525 3525);
WIRE 16 -1 (-1525 3575)(-1725 3575);
WIRE 16 -1 (-1525 3525)(-1525 3475);
WIRE 16 -1 (-1525 3525)(-1725 3525);
WIRE 16 -1 (-1525 3475)(-1525 3425);
WIRE 16 -1 (-1525 3475)(-1725 3475);
WIRE 16 -1 (-1525 3425)(-1525 3375);
WIRE 16 -1 (-1525 3425)(-1725 3425);
WIRE 16 -1 (-1525 3375)(-1525 3325);
WIRE 16 -1 (-1525 3375)(-1725 3375);
WIRE 16 -1 (-1525 3325)(-1525 3275);
WIRE 16 -1 (-1525 3325)(-1725 3325);
WIRE 16 -1 (-1525 3275)(-1525 3225);
WIRE 16 -1 (-1525 3275)(-1725 3275);
WIRE 16 -1 (-1525 3225)(-1525 3175);
WIRE 16 -1 (-1525 3225)(-1725 3225);
WIRE 16 -1 (-1525 3175)(-1525 3125);
WIRE 16 -1 (-1525 3175)(-1725 3175);
WIRE 16 -1 (-1525 3125)(-1525 3075);
WIRE 16 -1 (-1525 3125)(-1725 3125);
WIRE 16 -1 (-1525 3075)(-1725 3075);
WIRE 16 -1 (-1525 3075)(-1525 3025);
WIRE 16 -1 (-1525 3025)(-1525 2975);
WIRE 16 -1 (-1525 3025)(-1725 3025);
WIRE 16 -1 (-1525 2975)(-1525 2925);
WIRE 16 -1 (-1525 2975)(-1725 2975);
WIRE 16 -1 (-1525 2925)(-1525 2875);
WIRE 16 -1 (-1525 2925)(-1725 2925);
WIRE 16 -1 (-1525 2875)(-1525 2825);
WIRE 16 -1 (-1525 2875)(-1725 2875);
WIRE 16 -1 (-1525 2825)(-1525 2775);
WIRE 16 -1 (-1525 2825)(-1725 2825);
WIRE 16 -1 (-1525 2775)(-1525 2725);
WIRE 16 -1 (-1525 2775)(-1725 2775);
WIRE 16 -1 (-1525 2725)(-1525 2675);
WIRE 16 -1 (-1525 2725)(-1725 2725);
WIRE 16 -1 (-1525 2675)(-1525 2625);
WIRE 16 -1 (-1525 2675)(-1725 2675);
WIRE 16 -1 (-1525 2625)(-1525 2575);
WIRE 16 -1 (-1525 2625)(-1725 2625);
WIRE 16 -1 (-1525 2575)(-1525 2525);
WIRE 16 -1 (-1525 2575)(-1725 2575);
WIRE 16 -1 (-1525 2525)(-1525 2475);
WIRE 16 -1 (-1525 2525)(-1725 2525);
WIRE 16 -1 (-1525 2475)(-1525 2425);
WIRE 16 -1 (-1525 2475)(-1725 2475);
WIRE 16 -1 (-1525 2425)(-1525 2375);
WIRE 16 -1 (-1525 2425)(-1725 2425);
WIRE 16 -1 (-1525 2375)(-1525 2325);
WIRE 16 -1 (-1525 2375)(-1725 2375);
WIRE 16 -1 (-1525 2325)(-1525 2275);
WIRE 16 -1 (-1525 2325)(-1725 2325);
WIRE 16 -1 (-1525 2275)(-1525 2225);
WIRE 16 -1 (-1525 2275)(-1725 2275);
WIRE 16 -1 (-1525 2225)(-1525 2175);
WIRE 16 -1 (-1525 2225)(-1725 2225);
WIRE 16 -1 (-1525 2175)(-1525 2150);
WIRE 16 -1 (-1525 2175)(-1725 2175);
WIRE 16 -1 (-1525 2150)(-825 2150);
WIRE 16 -1 (-825 2150)(-825 2100);
WIRE 16 -1 (-1725 2075)(-1050 2075);
FORCEPROP 2 LAST SIG_NAME NCF_A1_CPU0_P0_GND
J 0
(-1560 2085);
DISPLAY 0.553191 (-1560 2085);
PAINT SKYBLUE (-1560 2085);
FORCEPROP 2 LASTPROP $XRERR UNIQUE?
J 0
(-1800 2085);
DISPLAY 0.638298 (-1800 2085);
PAINT MONO (-1800 2085);
DISPLAY INVISIBLE (-1800 2085);
WIRE 16 -1 (-1050 2075)(-1050 1900);
WIRE 16 -1 (-6850 4750)(-7275 4750);
WIRE 16 -1 (-7275 4750)(-7275 4700);
WIRE 16 -1 (-7275 4750)(-7525 4750);
WIRE 16 -1 (-7525 4750)(-7525 4800);
WIRE 16 -1 (-6850 4700)(-7275 4700);
WIRE 16 -1 (-7275 4700)(-7275 4650);
WIRE 16 -1 (-6850 4650)(-7275 4650);
WIRE 16 -1 (-7275 4650)(-7275 4600);
WIRE 16 -1 (-6850 4600)(-7275 4600);
WIRE 16 -1 (-7275 4600)(-7275 4550);
WIRE 16 -1 (-7275 4550)(-6850 4550);
WIRE 16 -1 (-5450 4400)(-5450 4350);
WIRE 16 -1 (-5450 4450)(-5450 4400);
WIRE 16 -1 (-5700 4400)(-5450 4400);
WIRE 16 -1 (-5450 4350)(-5450 4300);
WIRE 16 -1 (-5450 4350)(-5700 4350);
WIRE 16 -1 (-5450 4300)(-5700 4300);
WIRE 16 -1 (-5450 4450)(-5000 4450);
WIRE 16 -1 (-5700 4450)(-5450 4450);
WIRE 16 -1 (-5000 4450)(-5000 4500);
DOT 1 (-1525 4075);
DOT 1 (-1525 4125);
DOT 1 (-1525 4175);
DOT 1 (-1525 5375);
DOT 1 (-5450 4350);
DOT 1 (-7275 4600);
DOT 1 (-7275 4650);
DOT 1 (-7275 4700);
DOT 1 (-5450 3850);
DOT 1 (-5450 3900);
DOT 1 (-5450 4000);
DOT 1 (-5450 4050);
DOT 1 (-5450 4250);
DOT 1 (-5450 4400);
DOT 1 (-5475 4550);
DOT 1 (-5450 4450);
DOT 1 (-5475 4600);
DOT 1 (-5475 4700);
DOT 1 (-5475 4750);
DOT 1 (-4425 4750);
DOT 1 (-2875 1575);
DOT 1 (-2875 1525);
DOT 1 (-2875 1625);
DOT 1 (-2875 1725);
DOT 1 (-2875 1675);
DOT 1 (-2875 1775);
DOT 1 (-2875 1825);
DOT 1 (-2875 1875);
DOT 1 (-2875 1975);
DOT 1 (-2875 2025);
DOT 1 (-2875 2075);
DOT 1 (-2875 2125);
DOT 1 (-2875 1925);
DOT 1 (-2875 2175);
DOT 1 (-2875 2225);
DOT 1 (-2875 2275);
DOT 1 (-2875 2325);
DOT 1 (-2875 2375);
DOT 1 (-2875 2425);
DOT 1 (-2875 2525);
DOT 1 (-2875 2575);
DOT 1 (-2875 2625);
DOT 1 (-2875 2675);
DOT 1 (-2875 2475);
DOT 1 (-2875 2725);
DOT 1 (-2875 2775);
DOT 1 (-2875 2925);
DOT 1 (-2875 2875);
DOT 1 (-2875 3075);
DOT 1 (-2875 3025);
DOT 1 (-2875 3125);
DOT 1 (-2875 3175);
DOT 1 (-2875 2975);
DOT 1 (-2875 3375);
DOT 1 (-2875 3225);
DOT 1 (-2875 3275);
DOT 1 (-2875 3425);
DOT 1 (-2875 3325);
DOT 1 (-2875 3475);
DOT 1 (-2875 3525);
DOT 1 (-2875 3575);
DOT 1 (-2875 3675);
DOT 1 (-2875 3625);
DOT 1 (-2875 3725);
DOT 1 (-2875 3775);
DOT 1 (-1200 1575);
DOT 1 (-1200 1525);
DOT 1 (-1200 1625);
DOT 1 (-1200 1675);
DOT 1 (-1200 1725);
DOT 1 (-1525 2225);
DOT 1 (-1525 2275);
DOT 1 (-1525 2325);
DOT 1 (-1525 2375);
DOT 1 (-1525 2425);
DOT 1 (-1525 2525);
DOT 1 (-1525 2575);
DOT 1 (-1525 2625);
DOT 1 (-1525 2725);
DOT 1 (-1525 2675);
DOT 1 (-1525 2775);
DOT 1 (-1525 2875);
DOT 1 (-1525 3025);
DOT 1 (-1525 3075);
DOT 1 (-1525 3125);
DOT 1 (-1525 3175);
DOT 1 (-1525 3225);
DOT 1 (-1525 3275);
DOT 1 (-1525 3325);
DOT 1 (-1525 3375);
DOT 1 (-1525 3425);
DOT 1 (-1525 3475);
DOT 1 (-1525 3525);
DOT 1 (-1525 3575);
DOT 1 (-1525 3625);
DOT 1 (-1525 3675);
DOT 1 (-1525 3725);
DOT 1 (-1525 3775);
DOT 1 (-1200 1775);
DOT 1 (-2875 3825);
DOT 1 (-2875 3875);
DOT 1 (-2875 3925);
DOT 1 (-2875 4075);
DOT 1 (-2875 4125);
DOT 1 (-2875 4175);
DOT 1 (-2875 4225);
DOT 1 (-2875 4275);
DOT 1 (-2875 4325);
DOT 1 (-2875 4375);
DOT 1 (-2875 4425);
DOT 1 (-2875 4475);
DOT 1 (-2875 4575);
DOT 1 (-2875 4625);
DOT 1 (-2875 4675);
DOT 1 (-2875 4725);
DOT 1 (-2875 4525);
DOT 1 (-2875 3975);
DOT 1 (-2875 4025);
DOT 1 (-2875 4825);
DOT 1 (-2875 4875);
DOT 1 (-2875 4925);
DOT 1 (-2875 4975);
DOT 1 (-2875 5075);
DOT 1 (-2875 5125);
DOT 1 (-2875 5025);
DOT 1 (-2875 5325);
DOT 1 (-2875 5375);
DOT 1 (-2875 5425);
DOT 1 (-2875 5275);
DOT 1 (-2875 5475);
DOT 1 (-2875 5525);
DOT 1 (-2875 5225);
DOT 1 (-2875 5175);
DOT 1 (-1525 3825);
DOT 1 (-1525 3875);
DOT 1 (-1525 3925);
DOT 1 (-1525 3975);
DOT 1 (-1525 4025);
DOT 1 (-1525 4225);
DOT 1 (-1525 4275);
DOT 1 (-1525 4325);
DOT 1 (-1525 4375);
DOT 1 (-1525 4425);
DOT 1 (-1525 4475);
DOT 1 (-1525 4525);
DOT 1 (-1525 4575);
DOT 1 (-1525 4625);
DOT 1 (-1525 4675);
DOT 1 (-1525 4725);
DOT 1 (-1525 4775);
DOT 1 (-1525 4825);
DOT 1 (-1525 4875);
DOT 1 (-1525 4925);
DOT 1 (-1525 4975);
DOT 1 (-1525 5025);
DOT 1 (-1525 5075);
DOT 1 (-1525 5175);
DOT 1 (-1525 5125);
DOT 1 (-1525 5225);
DOT 1 (-1525 5275);
DOT 1 (-1525 5325);
DOT 1 (-1525 5425);
DOT 1 (-1525 5475);
DOT 1 (-1525 5525);
DOT 1 (-7275 4750);
DOT 1 (-5475 4650);
DOT 1 (-5375 3650);
DOT 1 (-5375 3600);
DOT 1 (-2875 2825);
DOT 1 (-1200 1975);
DOT 1 (-1200 1825);
DOT 1 (-5375 3550);
DOT 1 (-5450 3950);
DOT 1 (-5450 4150);
DOT 1 (-2875 4775);
DOT 1 (-1525 2475);
DOT 1 (-1525 2825);
DOT 1 (-1525 2925);
DOT 1 (-1525 2975);
DOT 1 (-1525 2175);
DOT 1 (-1200 1875);
DOT 1 (-1200 1925);
DOT 1 (-5450 4100);
DOT 1 (-5450 4200);
DOT 1 (-7400 3650);
QUIT
